(kicad_pcb
	(version 20241229)
	(generator "pcbnew")
	(generator_version "9.0")
	(general
		(thickness 1.294)
		(legacy_teardrops no)
	)
	(paper "A3")
	(title_block
		(title "Kintex 410T devboard")
		(date "2024-04-03")
		(rev "1.1.2")
		(comment 9 "footprints 829-834 of 975")
	)
	(layers
		(0 "F.Cu" mixed)
		(4 "In1.Cu" power)
		(6 "In2.Cu" power)
		(8 "In3.Cu" mixed)
		(10 "In4.Cu" power)
		(12 "In5.Cu" mixed)
		(14 "In6.Cu" power)
		(16 "In7.Cu" mixed)
		(18 "In8.Cu" power)
		(2 "B.Cu" mixed)
		(9 "F.Adhes" user "F.Adhesive")
		(11 "B.Adhes" user "B.Adhesive")
		(13 "F.Paste" user)
		(15 "B.Paste" user)
		(5 "F.SilkS" user "F.Silkscreen")
		(7 "B.SilkS" user "B.Silkscreen")
		(1 "F.Mask" user)
		(3 "B.Mask" user)
		(17 "Dwgs.User" user "User.Drawings")
		(19 "Cmts.User" user "User.Comments")
		(21 "Eco1.User" user "User.Eco1")
		(23 "Eco2.User" user "User.Eco2")
		(25 "Edge.Cuts" user)
		(27 "Margin" user)
		(31 "F.CrtYd" user "F.Courtyard")
		(29 "B.CrtYd" user "B.Courtyard")
		(35 "F.Fab" user)
		(33 "B.Fab" user)
	)
	(footprint "antmicro-footprints:R_0402_1005Metric"
		(layer "B.Cu")
		(at 159 185.9 -90)
		(descr "Resistor SMD 0402")
		(tags "resistor SMD 0402")
		(property "Reference" "R294"
			(at -3.6 -0.4 90)
			(layer "B.SilkS")
			(effects
				(font
					(size 0.7 0.7)
					(thickness 0.15)
				)
				(justify left bottom mirror)
			)
		)
		(property "Value" "R_47k_0402"
			(at 0 -1.4 90)
			(layer "B.Fab")
			(effects
				(font
					(size 0.7 0.7)
					(thickness 0.15)
				)
				(justify left bottom mirror)
			)
		)
		(property "Description" "SMD Chip Resistor, 47 kohm, ± 1%, 62.5 mW, 0402 [1005 Metric], Thick Film, General Purpose"
			(at 0 0 270)
			(layer "F.Fab")
			(hide yes)
			(effects
				(font
					(size 1.27 1.27)
					(thickness 0.15)
				)
			)
		)
		(property "Author" "Antmicro"
			(at -26.9 344.9 0)
			(layer "B.Fab")
			(hide yes)
			(effects
				(font
					(size 1 1)
					(thickness 0.15)
				)
				(justify mirror)
			)
		)
		(property "License" "Apache-2.0"
			(at -26.9 344.9 0)
			(layer "B.Fab")
			(hide yes)
			(effects
				(font
					(size 1 1)
					(thickness 0.15)
				)
				(justify mirror)
			)
		)
		(property "MPN" "CR0402-FX-4702GLF"
			(at -26.9 344.9 0)
			(layer "B.Fab")
			(hide yes)
			(effects
				(font
					(size 1 1)
					(thickness 0.15)
				)
				(justify mirror)
			)
		)
		(property "Manufacturer" "Bourns"
			(at -26.9 344.9 0)
			(layer "B.Fab")
			(hide yes)
			(effects
				(font
					(size 1 1)
					(thickness 0.15)
				)
				(justify mirror)
			)
		)
		(property "Tolerance" "1%"
			(at -26.9 344.9 0)
			(layer "B.Fab")
			(hide yes)
			(effects
				(font
					(size 1 1)
					(thickness 0.15)
				)
				(justify mirror)
			)
		)
		(property "Val" "47k"
			(at -26.9 344.9 0)
			(layer "B.Fab")
			(hide yes)
			(effects
				(font
					(size 1 1)
					(thickness 0.15)
				)
				(justify mirror)
			)
		)
		(sheetname "DC-DC Converters")
		(sheetfile "dc-dc.kicad_sch")
		(attr smd)
		(fp_rect
			(start -0.925 0.47)
			(end 0.925 -0.47)
			(stroke
				(width 0.05)
				(type default)
			)
			(fill no)
			(layer "B.CrtYd")
		)
		(fp_rect
			(start -0.5 0.25)
			(end 0.5 -0.25)
			(stroke
				(width 0.15)
				(type solid)
			)
			(fill no)
			(layer "B.Fab")
		)
		(pad "1" smd roundrect
			(at -0.48 0 270)
			(size 0.59 0.64)
			(layers "B.Cu" "B.Mask" "B.Paste")
			(roundrect_rratio 0.25)
			(net 1340 "/SUP_MCU.SW_STATE")
			(pintype "passive")
		)
		(pad "2" smd roundrect
			(at 0.48 0 270)
			(size 0.59 0.64)
			(layers "B.Cu" "B.Mask" "B.Paste")
			(roundrect_rratio 0.25)
			(net 701 "/DC-DC Converters/PB_CTRL_OUT")
			(pintype "passive")
		)
	)
	(footprint "antmicro-footprints:NetTie-2_SMD_Pad0.127mm"
		(layer "B.Cu")
		(at 252.501 148.4 -90)
		(descr "Net tie, 2 pin, 0.127mm  SMD pads")
		(tags "net tie")
		(property "Reference" "NT10"
			(at -0.128 1.345 90)
			(layer "B.SilkS")
			(hide yes)
			(effects
				(font
					(size 0.7 0.7)
					(thickness 0.15)
				)
				(justify left bottom mirror)
			)
		)
		(property "Value" "Net-Tie_2"
			(at 0 -1.199 90)
			(layer "B.Fab")
			(effects
				(font
					(size 0.7 0.7)
					(thickness 0.15)
				)
				(justify left bottom mirror)
			)
		)
		(property "Description" "Net tie, 2 pins"
			(at 0 0 270)
			(layer "F.Fab")
			(hide yes)
			(effects
				(font
					(size 1.27 1.27)
					(thickness 0.15)
				)
			)
		)
		(property "Author" "Antmicro"
			(at 104.101 400.901 0)
			(layer "B.Fab")
			(hide yes)
			(effects
				(font
					(size 1 1)
					(thickness 0.15)
				)
				(justify mirror)
			)
		)
		(property "License" "Apache-2.0"
			(at 104.101 400.901 0)
			(layer "B.Fab")
			(hide yes)
			(effects
				(font
					(size 1 1)
					(thickness 0.15)
				)
				(justify mirror)
			)
		)
		(property "MPN" ""
			(at 104.101 400.901 0)
			(layer "B.Fab")
			(hide yes)
			(effects
				(font
					(size 1 1)
					(thickness 0.15)
				)
				(justify mirror)
			)
		)
		(property "Manufacturer" ""
			(at 104.101 400.901 0)
			(layer "B.Fab")
			(hide yes)
			(effects
				(font
					(size 1 1)
					(thickness 0.15)
				)
				(justify mirror)
			)
		)
		(sheetname "FPGA Bank 14 & 15")
		(sheetfile "fpga-bank-14-15.kicad_sch")
		(attr exclude_from_pos_files)
		(net_tie_pad_groups "1, 2")
		(fp_poly
			(pts
				(xy -0.0635 0.0635) (xy 0.0625 0.0635) (xy 0.0625 -0.0635) (xy -0.0635 -0.0635)
			)
			(stroke
				(width 0)
				(type solid)
			)
			(fill yes)
			(layer "B.Cu")
		)
		(pad "1" smd roundrect
			(at -0.127 0 90)
			(size 0.127 0.127)
			(layers "B.Cu")
			(roundrect_rratio 0.5)
			(chamfer_ratio 0)
			(chamfer top_left bottom_left)
			(net 1295 "/USB_SPI.MOSI")
			(pinfunction "1")
			(pintype "passive")
		)
		(pad "2" smd roundrect
			(at 0.126 0 270)
			(size 0.127 0.127)
			(layers "B.Cu")
			(roundrect_rratio 0.5)
			(chamfer_ratio 0)
			(chamfer top_left bottom_left)
			(net 1321 "/SUP_MCU.MOSI")
			(pinfunction "2")
			(pintype "passive")
		)
	)
	(footprint "antmicro-footprints:QFN-2L_1.6x1x0.55mm"
		(layer "B.Cu")
		(at 264.75 93.2 90)
		(property "Reference" "D36"
			(at -2.45 -0.8 90)
			(layer "B.SilkS")
			(effects
				(font
					(size 0.7 0.7)
					(thickness 0.15)
				)
				(justify right bottom mirror)
			)
		)
		(property "Value" "ESDA25P35-1U1M"
			(at 0 -1.7 90)
			(layer "B.Fab")
			(effects
				(font
					(size 0.7 0.7)
					(thickness 0.15)
				)
				(justify right bottom mirror)
			)
		)
		(property "Description" "Unidirectional TVS, 30 kV, QFN-2L, 22 V, 195 pF"
			(at 0 0 90)
			(layer "F.Fab")
			(hide yes)
			(effects
				(font
					(size 1.27 1.27)
					(thickness 0.15)
				)
			)
		)
		(property "Author" "Antmicro"
			(at 357.95 -171.55 0)
			(layer "B.Fab")
			(hide yes)
			(effects
				(font
					(size 1 1)
					(thickness 0.15)
				)
				(justify mirror)
			)
		)
		(property "License" "Apache-2.0"
			(at 357.95 -171.55 0)
			(layer "B.Fab")
			(hide yes)
			(effects
				(font
					(size 1 1)
					(thickness 0.15)
				)
				(justify mirror)
			)
		)
		(property "MPN" "ESDA25P35-1U1M"
			(at 357.95 -171.55 0)
			(layer "B.Fab")
			(hide yes)
			(effects
				(font
					(size 1 1)
					(thickness 0.15)
				)
				(justify mirror)
			)
		)
		(property "Manufacturer" "STMicroelectronics"
			(at 357.95 -171.55 0)
			(layer "B.Fab")
			(hide yes)
			(effects
				(font
					(size 1 1)
					(thickness 0.15)
				)
				(justify mirror)
			)
		)
		(property "Public" "False"
			(at 357.95 -171.55 0)
			(layer "B.Fab")
			(hide yes)
			(effects
				(font
					(size 1 1)
					(thickness 0.15)
				)
				(justify mirror)
			)
		)
		(sheetname "User GPIO + LED + button + DIP switch")
		(sheetfile "user-gpio.kicad_sch")
		(attr smd)
		(fp_line
			(start 0.27 -0.3)
			(end -0.27 -0.3)
			(stroke
				(width 0.15)
				(type solid)
			)
			(layer "B.SilkS")
		)
		(fp_line
			(start 0.27 0.3)
			(end -0.27 0.3)
			(stroke
				(width 0.15)
				(type solid)
			)
			(layer "B.SilkS")
		)
		(fp_line
			(start -1.2 0.4)
			(end -1.2 -0.4)
			(stroke
				(width 0.15)
				(type solid)
			)
			(layer "B.SilkS")
		)
		(fp_rect
			(start 1.25 -0.65)
			(end -1.25 0.65)
			(stroke
				(width 0.05)
				(type solid)
			)
			(fill no)
			(layer "B.CrtYd")
		)
		(fp_line
			(start 0.201 -0.2)
			(end 0.201 0)
			(stroke
				(width 0.15)
				(type solid)
			)
			(layer "B.Fab")
		)
		(fp_line
			(start -0.199 -0.2)
			(end -0.199 -0.1)
			(stroke
				(width 0.15)
				(type solid)
			)
			(layer "B.Fab")
		)
		(fp_line
			(start 0.599 0)
			(end 0.201 0)
			(stroke
				(width 0.15)
				(type solid)
			)
			(layer "B.Fab")
		)
		(fp_line
			(start 0.201 0)
			(end 0.201 0.202)
			(stroke
				(width 0.15)
				(type solid)
			)
			(layer "B.Fab")
		)
		(fp_line
			(start -0.101 0)
			(end 0.201 -0.2)
			(stroke
				(width 0.15)
				(type solid)
			)
			(layer "B.Fab")
		)
		(fp_line
			(start -0.199 0)
			(end -0.597 0)
			(stroke
				(width 0.15)
				(type solid)
			)
			(layer "B.Fab")
		)
		(fp_line
			(start 0.201 0.202)
			(end -0.101 0)
			(stroke
				(width 0.15)
				(type solid)
			)
			(layer "B.Fab")
		)
		(fp_line
			(start -0.199 0.202)
			(end -0.199 -0.1)
			(stroke
				(width 0.15)
				(type solid)
			)
			(layer "B.Fab")
		)
		(fp_rect
			(start 0.848 -0.4)
			(end -0.85 0.402)
			(stroke
				(width 0.15)
				(type solid)
			)
			(fill no)
			(layer "B.Fab")
		)
		(pad "1" smd roundrect
			(at -0.7 0 270)
			(size 0.8 1)
			(layers "B.Cu" "B.Mask" "B.Paste")
			(roundrect_rratio 0.2)
			(net 1232 "/USER_IO.BUTTON3")
			(pinfunction "C")
			(pintype "passive")
		)
		(pad "2" smd roundrect
			(at 0.7 0 270)
			(size 0.8 1)
			(layers "B.Cu" "B.Mask" "B.Paste")
			(roundrect_rratio 0.2)
			(net 1 "GND")
			(pinfunction "A")
			(pintype "passive")
		)
	)
	(footprint "antmicro-footprints:R_0402_1005Metric"
		(layer "B.Cu")
		(at 191.8 133.3 180)
		(descr "Resistor SMD 0402")
		(tags "resistor SMD 0402")
		(property "Reference" "R1"
			(at -22.375 28.1 0)
			(layer "B.SilkS")
			(effects
				(font
					(size 0.7 0.7)
					(thickness 0.15)
				)
				(justify left bottom mirror)
			)
		)
		(property "Value" "R_100R_0402"
			(at 0 -1.4 0)
			(layer "B.Fab")
			(effects
				(font
					(size 0.7 0.7)
					(thickness 0.15)
				)
				(justify left bottom mirror)
			)
		)
		(property "Description" "SMD Chip Resistor, 100 ohm, ± 1%, 62.5 mW, 0402 [1005 Metric], Thick Film, General Purpose"
			(at 0 0 180)
			(layer "F.Fab")
			(hide yes)
			(effects
				(font
					(size 1.27 1.27)
					(thickness 0.15)
				)
			)
		)
		(property "Author" "Antmicro"
			(at 383.6 266.6 0)
			(layer "B.Fab")
			(hide yes)
			(effects
				(font
					(size 1 1)
					(thickness 0.15)
				)
				(justify mirror)
			)
		)
		(property "License" "Apache-2.0"
			(at 383.6 266.6 0)
			(layer "B.Fab")
			(hide yes)
			(effects
				(font
					(size 1 1)
					(thickness 0.15)
				)
				(justify mirror)
			)
		)
		(property "MPN" "CR0402-FX-1000GLF"
			(at 383.6 266.6 0)
			(layer "B.Fab")
			(hide yes)
			(effects
				(font
					(size 1 1)
					(thickness 0.15)
				)
				(justify mirror)
			)
		)
		(property "Manufacturer" "Bourns"
			(at 383.6 266.6 0)
			(layer "B.Fab")
			(hide yes)
			(effects
				(font
					(size 1 1)
					(thickness 0.15)
				)
				(justify mirror)
			)
		)
		(property "Tolerance" "1%"
			(at 383.6 266.6 0)
			(layer "B.Fab")
			(hide yes)
			(effects
				(font
					(size 1 1)
					(thickness 0.15)
				)
				(justify mirror)
			)
		)
		(property "Val" "100R"
			(at 383.6 266.6 0)
			(layer "B.Fab")
			(hide yes)
			(effects
				(font
					(size 1 1)
					(thickness 0.15)
				)
				(justify mirror)
			)
		)
		(sheetname "FPGA supply")
		(sheetfile "fpga-supply.kicad_sch")
		(attr smd)
		(fp_rect
			(start -0.925 0.47)
			(end 0.925 -0.47)
			(stroke
				(width 0.05)
				(type default)
			)
			(fill no)
			(layer "B.CrtYd")
		)
		(fp_rect
			(start -0.5 0.25)
			(end 0.5 -0.25)
			(stroke
				(width 0.15)
				(type solid)
			)
			(fill no)
			(layer "B.Fab")
		)
		(pad "1" smd roundrect
			(at -0.48 0 180)
			(size 0.59 0.64)
			(layers "B.Cu" "B.Mask" "B.Paste")
			(roundrect_rratio 0.25)
			(net 494 "/FPGA supply/MGTRREF")
			(pintype "passive")
		)
		(pad "2" smd roundrect
			(at 0.48 0 180)
			(size 0.59 0.64)
			(layers "B.Cu" "B.Mask" "B.Paste")
			(roundrect_rratio 0.25)
			(net 8 "+1V2_MGTAVTT")
			(pintype "passive")
		)
	)
	(footprint "antmicro-footprints:C_0603_1608Metric"
		(layer "B.Cu")
		(at 200 144.4 90)
		(descr "Capacitor SMD 0603")
		(tags "capacitor 0603")
		(property "Reference" "C49"
			(at -1.09 1.42 90)
			(layer "B.SilkS")
			(effects
				(font
					(size 0.7 0.7)
					(thickness 0.15)
				)
				(justify right bottom mirror)
			)
		)
		(property "Value" "C_47u_0603"
			(at 0 -1.6 90)
			(layer "B.Fab")
			(effects
				(font
					(size 0.7 0.7)
					(thickness 0.15)
				)
				(justify right bottom mirror)
			)
		)
		(property "Description" "SMD Multilayer Ceramic Capacitor, 47 µF, 6.3 V, 0603 [1608 Metric], ± 20%, X5R, GRM Series"
			(at 0 0 90)
			(layer "F.Fab")
			(hide yes)
			(effects
				(font
					(size 1.27 1.27)
					(thickness 0.15)
				)
			)
		)
		(property "Author" "Antmicro"
			(at 344.4 -55.6 0)
			(layer "B.Fab")
			(hide yes)
			(effects
				(font
					(size 1 1)
					(thickness 0.15)
				)
				(justify mirror)
			)
		)
		(property "Dielectric" ""
			(at 344.4 -55.6 0)
			(layer "B.Fab")
			(hide yes)
			(effects
				(font
					(size 1 1)
					(thickness 0.15)
				)
				(justify mirror)
			)
		)
		(property "License" "Apache-2.0"
			(at 344.4 -55.6 0)
			(layer "B.Fab")
			(hide yes)
			(effects
				(font
					(size 1 1)
					(thickness 0.15)
				)
				(justify mirror)
			)
		)
		(property "MPN" "GRM188R60J476ME15D"
			(at 344.4 -55.6 0)
			(layer "B.Fab")
			(hide yes)
			(effects
				(font
					(size 1 1)
					(thickness 0.15)
				)
				(justify mirror)
			)
		)
		(property "Manufacturer" "Murata"
			(at 344.4 -55.6 0)
			(layer "B.Fab")
			(hide yes)
			(effects
				(font
					(size 1 1)
					(thickness 0.15)
				)
				(justify mirror)
			)
		)
		(property "Val" "47u"
			(at 344.4 -55.6 0)
			(layer "B.Fab")
			(hide yes)
			(effects
				(font
					(size 1 1)
					(thickness 0.15)
				)
				(justify mirror)
			)
		)
		(property "Voltage" ""
			(at 344.4 -55.6 0)
			(layer "B.Fab")
			(hide yes)
			(effects
				(font
					(size 1 1)
					(thickness 0.15)
				)
				(justify mirror)
			)
		)
		(sheetname "FPGA supply")
		(sheetfile "fpga-supply.kicad_sch")
		(attr smd)
		(fp_line
			(start -0.15 -0.4)
			(end 0.15 -0.4)
			(stroke
				(width 0.15)
				(type solid)
			)
			(layer "B.SilkS")
		)
		(fp_line
			(start -0.15 0.4)
			(end 0.15 0.4)
			(stroke
				(width 0.15)
				(type solid)
			)
			(layer "B.SilkS")
		)
		(fp_rect
			(start -1.25 0.65)
			(end 1.25 -0.65)
			(stroke
				(width 0.05)
				(type solid)
			)
			(fill no)
			(layer "B.CrtYd")
		)
		(fp_rect
			(start -0.8 0.4)
			(end 0.8 -0.4)
			(stroke
				(width 0.15)
				(type solid)
			)
			(fill no)
			(layer "B.Fab")
		)
		(pad "1" smd roundrect
			(at -0.7 0 90)
			(size 0.8 1)
			(layers "B.Cu" "B.Mask" "B.Paste")
			(roundrect_rratio 0.2)
			(net 1 "GND")
			(pintype "passive")
		)
		(pad "2" smd roundrect
			(at 0.7 0 90)
			(size 0.8 1)
			(layers "B.Cu" "B.Mask" "B.Paste")
			(roundrect_rratio 0.2)
			(net 26 "+1V8")
			(pintype "passive")
		)
	)
	(footprint "antmicro-footprints:R_0402_1005Metric"
		(layer "B.Cu")
		(at 265.901 145.35)
		(descr "Resistor SMD 0402")
		(tags "resistor SMD 0402")
		(property "Reference" "R57"
			(at -3.851 0.325 180)
			(layer "B.SilkS")
			(effects
				(font
					(size 0.7 0.7)
					(thickness 0.15)
				)
				(justify left bottom mirror)
			)
		)
		(property "Value" "R_1k_0402"
			(at 0 -1.4 180)
			(layer "B.Fab")
			(effects
				(font
					(size 0.7 0.7)
					(thickness 0.15)
				)
				(justify left bottom mirror)
			)
		)
		(property "Description" "SMD Chip Resistor, 1 kohm, ± 1%, 63 mW, 0402 [1005 Metric], Thick Film, General Purpose"
			(at 0 0 0)
			(layer "F.Fab")
			(hide yes)
			(effects
				(font
					(size 1.27 1.27)
					(thickness 0.15)
				)
			)
		)
		(property "Author" "Antmicro"
			(at 0 0 0)
			(layer "B.Fab")
			(hide yes)
			(effects
				(font
					(size 1 1)
					(thickness 0.15)
				)
				(justify mirror)
			)
		)
		(property "License" "Apache-2.0"
			(at 0 0 0)
			(layer "B.Fab")
			(hide yes)
			(effects
				(font
					(size 1 1)
					(thickness 0.15)
				)
				(justify mirror)
			)
		)
		(property "MPN" "CR0402-FX-1001GLF"
			(at 0 0 0)
			(layer "B.Fab")
			(hide yes)
			(effects
				(font
					(size 1 1)
					(thickness 0.15)
				)
				(justify mirror)
			)
		)
		(property "Manufacturer" "Bourns"
			(at 0 0 0)
			(layer "B.Fab")
			(hide yes)
			(effects
				(font
					(size 1 1)
					(thickness 0.15)
				)
				(justify mirror)
			)
		)
		(property "Tolerance" "1%"
			(at 0 0 0)
			(layer "B.Fab")
			(hide yes)
			(effects
				(font
					(size 1 1)
					(thickness 0.15)
				)
				(justify mirror)
			)
		)
		(property "Val" "1k"
			(at 0 0 0)
			(layer "B.Fab")
			(hide yes)
			(effects
				(font
					(size 1 1)
					(thickness 0.15)
				)
				(justify mirror)
			)
		)
		(sheetname "Power supply")
		(sheetfile "power-supply.kicad_sch")
		(attr smd)
		(fp_rect
			(start -0.925 0.47)
			(end 0.925 -0.47)
			(stroke
				(width 0.05)
				(type default)
			)
			(fill no)
			(layer "B.CrtYd")
		)
		(fp_rect
			(start -0.5 0.25)
			(end 0.5 -0.25)
			(stroke
				(width 0.15)
				(type solid)
			)
			(fill no)
			(layer "B.Fab")
		)
		(pad "1" smd roundrect
			(at -0.48 0)
			(size 0.59 0.64)
			(layers "B.Cu" "B.Mask" "B.Paste")
			(roundrect_rratio 0.25)
			(net 700 "/Power supply/USB_PD_VBUS")
			(pintype "passive")
		)
		(pad "2" smd roundrect
			(at 0.48 0)
			(size 0.59 0.64)
			(layers "B.Cu" "B.Mask" "B.Paste")
			(roundrect_rratio 0.25)
			(net 20 "Net-(D13-A)")
			(pintype "passive")
		)
	)
)
